# T6G (Grand Teton) — schematic netlist excerpt (pin names and nets, part order shuffled) for the footprints in the layout excerpt that follows; sources: Cadence DE-HDL packaged netlist, KiCad conversion of 04192023_DAF0TMB3IC0_F0TG_MB_C_brd_V02_OCP.brd

J27  SCONN288_DDR506112002KQ  IO  pkg DDR288S_1-1VXC  page 105
  VIN_BULK0  = P12V_MEM_CPU1
  RFU0  = NC
  VIN_MGMT  = P3V3_AUX
  HSCL  = I3C_SPD_DDRH_CPU1_SCL
  HSDA  = I3C_SPD_DDRH_CPU1_SDA
  VSS0  = GND
  DQ0_A  = M_H_CPU1_SA_DQ<0>
  VSS1  = GND
  DQ1_A  = M_H_CPU1_SA_DQ<1>
  VSS2  = GND
  DQS0_A_T  = M_H_CPU1_SA_DQS_DP<0>
  DQS0_A_C  = M_H_CPU1_SA_DQS_DN<0>
  VSS3  = GND
  DQ4_A  = M_H_CPU1_SA_DQ<4>
  VSS4  = GND
  DQ5_A  = M_H_CPU1_SA_DQ<5>
  VSS5  = GND
  DQ8_A  = M_H_CPU1_SA_DQ<8>
  VSS6  = GND
  DQ9_A  = M_H_CPU1_SA_DQ<9>
  VSS7  = GND
  DQS1_A_T  = M_H_CPU1_SA_DQS_DP<1>
  DQS1_A_C  = M_H_CPU1_SA_DQS_DN<1>
  VSS8  = GND
  DQ12_A  = M_H_CPU1_SA_DQ<12>
  VSS9  = GND
  DQ13_A  = M_H_CPU1_SA_DQ<13>
  VSS10  = GND
  DQ16_A  = M_H_CPU1_SA_DQ<16>
  VSS11  = GND
  DQ17_A  = M_H_CPU1_SA_DQ<17>
  VSS12  = GND
  DQS2_A_T  = M_H_CPU1_SA_DQS_DP<2>
  DQS2_A_C  = M_H_CPU1_SA_DQS_DN<2>
  VSS13  = GND
  DQ20_A  = M_H_CPU1_SA_DQ<20>
  VSS14  = GND
  DQ21_A  = M_H_CPU1_SA_DQ<21>
  VSS15  = GND
  DQ24_A  = M_H_CPU1_SA_DQ<24>
  VSS16  = GND
  DQ25_A  = M_H_CPU1_SA_DQ<25>
  VSS17  = GND
  DQS3_A_T  = M_H_CPU1_SA_DQS_DP<3>
  DQS3_A_C  = M_H_CPU1_SA_DQS_DN<3>
  VSS18  = GND
  DQ28_A  = M_H_CPU1_SA_DQ<28>
  VSS19  = GND
  DQ29_A  = M_H_CPU1_SA_DQ<29>
  VSS20  = GND
  CB0_A  = M_H_CPU1_SA_CB<0>
  VSS21  = GND
  CB1_A  = M_H_CPU1_SA_CB<1>
  VSS22  = GND
  DQS4_A_T  = M_H_CPU1_SA_DQS_DP<4>
  DQS4_A_C  = M_H_CPU1_SA_DQS_DN<4>
  VSS23  = GND
  CB4_A  = M_H_CPU1_SA_CB<4>
  VSS24  = GND
  CB5_A  = M_H_CPU1_SA_CB<5>
  VSS25  = GND
  ALERT_N  = M_H_CPU1_ALERT_N
  VSS26  = GND
  CS0_A_N  = M_H_CPU1_SA_CS_N<0>
  VSS27  = GND
  CA0_A  = M_H_CPU1_SA_CA<0>
  VSS28  = GND
  CA2_A  = M_H_CPU1_SA_CA<2>
  VSS29  = GND
  CA4_A  = M_H_CPU1_SA_CA<4>
  VSS30  = GND
  CA6_A  = M_H_CPU1_SA_CA<6>
  VSS31  = GND
  PAR_A  = M_H_CPU1_SA_PAR
  VSS32  = GND
  CA0_B  = M_H_CPU1_SB_CA<0>
  VSS33  = GND
  CA2_B  = M_H_CPU1_SB_CA<2>
  VSS34  = GND
  CA4_B  = M_H_CPU1_SB_CA<4>
  VSS35  = GND
  CA6_B  = M_H_CPU1_SB_CA<6>
  VSS36  = GND
  CS0_B_N  = M_H_CPU1_SB_CS_N<0>
  VSS37  = GND
  \lbd||rsp_a_n\  = M_H_CPU1_SA_RSP<0>
  \lbs||rsp_b_n\  = M_H_CPU1_SB_RSP<0>
  VSS38  = GND
  CB4_B  = M_H_CPU1_SB_CB<4>
  VSS39  = GND
  CB5_B  = M_H_CPU1_SB_CB<5>
  VSS40  = GND
  \dqs9_b_t||tdqs9_b_t||dbi4_b_n\  = M_H_CPU1_SB_DQS_DP<9>
  \dqs9_b_c||tdqs9_b_c\  = M_H_CPU1_SB_DQS_DN<9>
  VSS41  = GND
  CB0_B  = M_H_CPU1_SB_CB<0>
  VSS42  = GND
  CB1_B  = M_H_CPU1_SB_CB<1>
  VSS43  = GND
  DQ0_B  = M_H_CPU1_SB_DQ<0>
  VSS44  = GND
  DQ1_B  = M_H_CPU1_SB_DQ<1>
  VSS45  = GND
  DQS0_B_T  = M_H_CPU1_SB_DQS_DP<0>
  DQS0_B_C  = M_H_CPU1_SB_DQS_DN<0>
  VSS46  = GND
  DQ4_B  = M_H_CPU1_SB_DQ<4>
  VSS47  = GND
  DQ5_B  = M_H_CPU1_SB_DQ<5>
  VSS48  = GND
  DQ8_B  = M_H_CPU1_SB_DQ<8>
  VSS49  = GND
  DQ9_B  = M_H_CPU1_SB_DQ<9>
  VSS50  = GND
  DQS1_B_T  = M_H_CPU1_SB_DQS_DP<1>
  DQS1_B_C  = M_H_CPU1_SB_DQS_DN<1>
  VSS51  = GND
  DQ12_B  = M_H_CPU1_SB_DQ<12>
  VSS52  = GND
  DQ13_B  = M_H_CPU1_SB_DQ<13>
  VSS53  = GND
  DQ16_B  = M_H_CPU1_SB_DQ<16>
  VSS54  = GND
  DQ17_B  = M_H_CPU1_SB_DQ<17>
  VSS55  = GND
  DQS2_B_T  = M_H_CPU1_SB_DQS_DP<2>
  DQS2_B_C  = M_H_CPU1_SB_DQS_DN<2>
  VSS56  = GND
  DQ20_B  = M_H_CPU1_SB_DQ<20>
  VSS57  = GND
  DQ21_B  = M_H_CPU1_SB_DQ<21>
  VSS58  = GND
  DQ24_B  = M_H_CPU1_SB_DQ<24>
  VSS59  = GND
  DQ25_B  = M_H_CPU1_SB_DQ<25>
  VSS60  = GND
  DQS3_B_T  = M_H_CPU1_SB_DQS_DP<3>
  DQS3_B_C  = M_H_CPU1_SB_DQS_DN<3>
  VSS61  = GND
  DQ28_B  = M_H_CPU1_SB_DQ<28>
  VSS62  = GND
  DQ29_B  = M_H_CPU1_SB_DQ<29>
  VSS63  = GND
  RFU1  = NC
  VIN_BULK1  = P12V_MEM_CPU1
  VIN_BULK2  = P12V_MEM_CPU1
  \pwr_good||fail_n\  = PWRGD_CHH_CPU1_DIMM
  HAS  = PD_CHH_CPU1_DIMM_SAA
  RFU2  = NC
  RFU3  = NC
  VSS64  = GND
  DQ2_A  = M_H_CPU1_SA_DQ<2>
  VSS65  = GND
  DQ3_A  = M_H_CPU1_SA_DQ<3>
  VSS66  = GND
  \dqs5_a_c||tdqs5_a_c||dqs5_a_t||tdqs5_a_t\  = M_H_CPU1_SA_DQS_DN<5>
  \dqs5_a_t||tdqs5_a_t\  = M_H_CPU1_SA_DQS_DP<5>
  VSS67  = GND
  DQ6_A  = M_H_CPU1_SA_DQ<6>
  VSS68  = GND
  DQ7_A  = M_H_CPU1_SA_DQ<7>
  VSS69  = GND
  DQ10_A  = M_H_CPU1_SA_DQ<10>
  VSS70  = GND
  DQ11_A  = M_H_CPU1_SA_DQ<11>
  VSS71  = GND
  \dqs6_a_c||tdqs6_a_c||dqs6_a_t||tdqs6_a_t\  = M_H_CPU1_SA_DQS_DN<6>
  \dqs6_a_t||tdqs6_a_t\  = M_H_CPU1_SA_DQS_DP<6>
  VSS72  = GND
  DQ14_A  = M_H_CPU1_SA_DQ<14>
  VSS73  = GND
  DQ15_A  = M_H_CPU1_SA_DQ<15>
  VSS74  = GND
  DQ18_A  = M_H_CPU1_SA_DQ<18>
  VSS75  = GND
  DQ19_A  = M_H_CPU1_SA_DQ<19>
  VSS76  = GND
  \dqs7_a_c||tdqs7_a_c\  = M_H_CPU1_SA_DQS_DN<7>
  \dqs7_a_t||tdqs7_a_t\  = M_H_CPU1_SA_DQS_DP<7>
  VSS77  = GND
  DQ22_A  = M_H_CPU1_SA_DQ<22>
  VSS78  = GND
  DQ23_A  = M_H_CPU1_SA_DQ<23>
  VSS79  = GND
  DQ26_A  = M_H_CPU1_SA_DQ<26>
  VSS80  = GND
  DQ27_A  = M_H_CPU1_SA_DQ<27>
  VSS81  = GND
  \dqs8_a_c||tdqs8_a_c\  = M_H_CPU1_SA_DQS_DN<8>
  \dqs8_a_t||tdqs8_a_t\  = M_H_CPU1_SA_DQS_DP<8>
  VSS82  = GND
  DQ30_A  = M_H_CPU1_SA_DQ<30>
  VSS83  = GND
  DQ31_A  = M_H_CPU1_SA_DQ<31>
  VSS84  = GND
  CB2_A  = M_H_CPU1_SA_CB<2>
  VSS85  = GND
  CB3_A  = M_H_CPU1_SA_CB<3>
  VSS86  = GND
  \dqs9_a_c||tdqs9_a_c\  = M_H_CPU1_SA_DQS_DN<9>
  \dqs9_a_t||tdqs9_a_t\  = M_H_CPU1_SA_DQS_DP<9>
  VSS87  = GND
  CB6_A  = M_H_CPU1_SA_CB<6>
  VSS88  = GND
  CB7_A  = M_H_CPU1_SA_CB<7>
  VSS89  = GND
  RESET_N  = M_H_CPU1_RESET_N
  VSS90  = GND
  CS1_A_N  = M_H_CPU1_SA_CS_N<1>
  VSS91  = GND
  CA1_A  = M_H_CPU1_SA_CA<1>
  VSS92  = GND
  CA3_A  = M_H_CPU1_SA_CA<3>
  VSS93  = GND
  CA5_A  = M_H_CPU1_SA_CA<5>
  VSS94  = GND
  CK_T  = M_H_CPU1_CLK_DP<0>
  CK_C  = M_H_CPU1_CLK_DN<0>
  VSS95  = GND
  RFU4  = NC
  CA1_B  = M_H_CPU1_SB_CA<1>
  VSS96  = GND
  CA3_B  = M_H_CPU1_SB_CA<3>
  VSS97  = GND
  CA5_B  = M_H_CPU1_SB_CA<5>
  VSS98  = GND
  PAR_B  = M_H_CPU1_SB_PAR
  VSS99  = GND
  CS1_B_N  = M_H_CPU1_SB_CS_N<1>
  VSS100  = GND
  RFU5  = NC
  RFU6  = NC
  VSS101  = GND
  CB6_B  = M_H_CPU1_SB_CB<6>
  VSS102  = GND
  CB7_B  = M_H_CPU1_SB_CB<7>
  VSS103  = GND
  DQS4_B_C  = M_H_CPU1_SB_DQS_DN<4>
  DQS4_B_T  = M_H_CPU1_SB_DQS_DP<4>
  VSS104  = GND
  CB2_B  = M_H_CPU1_SB_CB<2>
  VSS105  = GND
  CB3_B  = M_H_CPU1_SB_CB<3>
  VSS106  = GND
  DQ2_B  = M_H_CPU1_SB_DQ<2>
  VSS107  = GND
  DQ3_B  = M_H_CPU1_SB_DQ<3>
  VSS108  = GND
  \dqs5_b_c||tdqs5_b_c\  = M_H_CPU1_SB_DQS_DN<5>
  \dqs5_b_t||tdqs5_b_t\  = M_H_CPU1_SB_DQS_DP<5>
  VSS109  = GND
  DQ6_B  = M_H_CPU1_SB_DQ<6>
  VSS110  = GND
  DQ7_B  = M_H_CPU1_SB_DQ<7>
  VSS111  = GND
  DQ10_B  = M_H_CPU1_SB_DQ<10>
  VSS112  = GND
  DQ11_B  = M_H_CPU1_SB_DQ<11>
  VSS113  = GND
  \dqs6_b_c||tdqs6_b_c\  = M_H_CPU1_SB_DQS_DN<6>
  \dqs6_b_t||tdqs6_b_t\  = M_H_CPU1_SB_DQS_DP<6>
  VSS114  = GND
  DQ14_B  = M_H_CPU1_SB_DQ<14>
  VSS115  = GND
  DQ15_B  = M_H_CPU1_SB_DQ<15>
  VSS116  = GND
  DQ18_B  = M_H_CPU1_SB_DQ<18>
  VSS117  = GND
  DQ19_B  = M_H_CPU1_SB_DQ<19>
  VSS118  = GND
  \dqs7_b_c||tdqs7_b_c\  = M_H_CPU1_SB_DQS_DN<7>
  \dqs7_b_t||tdqs7_b_t\  = M_H_CPU1_SB_DQS_DP<7>
  VSS119  = GND
  DQ22_B  = M_H_CPU1_SB_DQ<22>
  VSS120  = GND
  DQ23_B  = M_H_CPU1_SB_DQ<23>
  VSS121  = GND
  DQ26_B  = M_H_CPU1_SB_DQ<26>
  VSS122  = GND
  DQ27_B  = M_H_CPU1_SB_DQ<27>
  VSS123  = GND
  \dqs8_b_c||tdqs8_b_c\  = M_H_CPU1_SB_DQS_DN<8>
  \dqs8_b_t||tdqs8_b_t\  = M_H_CPU1_SB_DQS_DP<8>
  VSS124  = GND
  DQ30_B  = M_H_CPU1_SB_DQ<30>
  VSS125  = GND
  DQ31_B  = M_H_CPU1_SB_DQ<31>
  VSS126  = GND
  G1  = GND
  G2  = GND
  G3  = GND

(kicad_pcb
	(version 20260206)
	(generator "pcbnew")
	(generator_version "10.0")
	(general
		(thickness 1.6)
		(legacy_teardrops no)
	)
	(paper "A4")
	(title_block
		(title "04192023_DAF0TMB3IC0_F0TG_MB_C_brd_V02_OCP.brd")
		(comment 1 "Grand Teton / footprint 583 of 8354 (J27), pads 231-276 of 291")
	)
	(layers
		(0 "F.Cu" signal "TOP")
		(4 "In1.Cu" signal "GND")
		(6 "In2.Cu" signal "IN1")
		(8 "In3.Cu" signal "GND1")
		(10 "In4.Cu" signal "IN2")
		(12 "In5.Cu" signal "GND2")
		(14 "In6.Cu" signal "IN3")
		(16 "In7.Cu" signal "GND3")
		(18 "In8.Cu" signal "VCC")
		(20 "In9.Cu" signal "VCC1")
		(22 "In10.Cu" signal "GND4")
		(24 "In11.Cu" signal "IN4")
		(26 "In12.Cu" signal "GND5")
		(28 "In13.Cu" signal "IN5")
		(30 "In14.Cu" signal "GND6")
		(32 "In15.Cu" signal "IN6")
		(34 "In16.Cu" signal "GND7")
		(2 "B.Cu" signal "BOTTOM")
		(9 "F.Adhes" user "F.Adhesive")
		(11 "B.Adhes" user "B.Adhesive")
		(13 "F.Paste" user "Package Geometry/Pastemask Top")
		(15 "B.Paste" user "Package Geometry/Pastemask Bottom")
		(5 "F.SilkS" user "Ref Des/Silkscreen Top")
		(7 "B.SilkS" user "Ref Des/Silkscreen Bottom")
		(1 "F.Mask" user "Board Geometry/Soldermask Top")
		(3 "B.Mask" user "Board Geometry/Soldermask Bottom")
		(17 "Dwgs.User" user "User.Drawings")
		(19 "Cmts.User" user "User.Comments")
		(21 "Eco1.User" user "User.Eco1")
		(23 "Eco2.User" user "User.Eco2")
		(25 "Edge.Cuts" user "Board Geometry/Outline")
		(27 "Margin" user)
		(31 "F.CrtYd" user "Package Geometry/Place Bound Top")
		(29 "B.CrtYd" user "Package Geometry/Place Bound Bottom")
		(35 "F.Fab" user "Ref Des/Assembly Top")
		(33 "B.Fab" user "Ref Des/Assembly Bottom")
	)
	(footprint ""
		(layer "F.Cu")
		(at 174.022004 -255.560322 180)
		(property "Reference" "J27"
			(at -2.7178 -81.857088 0)
			(unlocked yes)
			(layer "F.SilkS")
			(effects
				(font
					(size 0.7874 0.5842)
					(thickness 0.1524)
				)
			)
		)
		(property "Value" ""
			(at 0 0 180)
			(layer "F.Fab")
			(effects
				(font
					(size 1.27 1.27)
				)
			)
		)
		(duplicate_pad_numbers_are_jumpers no)
		(pad "231" smd rect
			(at 2.050034 14.875002 90)
			(size 0.519938 1.4986)
			(layers "F.Cu" "F.Mask" "F.Paste")
			(net "Net_2359")
		)
		(pad "232" smd rect
			(at 2.050034 15.724886 90)
			(size 0.519938 1.4986)
			(layers "F.Cu" "F.Mask" "F.Paste")
			(net "Net_2360")
		)
		(pad "233" smd rect
			(at 2.050034 16.575024 90)
			(size 0.519938 1.4986)
			(layers "F.Cu" "F.Mask" "F.Paste")
			(net "GND")
		)
		(pad "234" smd rect
			(at 2.050034 17.424908 90)
			(size 0.519938 1.4986)
			(layers "F.Cu" "F.Mask" "F.Paste")
			(net "M_H_CPU1_SB_CB<6>")
		)
		(pad "235" smd rect
			(at 2.050034 18.275046 90)
			(size 0.519938 1.4986)
			(layers "F.Cu" "F.Mask" "F.Paste")
			(net "GND")
		)
		(pad "236" smd rect
			(at 2.050034 19.12493 90)
			(size 0.519938 1.4986)
			(layers "F.Cu" "F.Mask" "F.Paste")
			(net "M_H_CPU1_SB_CB<7>")
		)
		(pad "237" smd rect
			(at 2.050034 19.975068 90)
			(size 0.519938 1.4986)
			(layers "F.Cu" "F.Mask" "F.Paste")
			(net "GND")
		)
		(pad "238" smd rect
			(at 2.050034 20.824952 90)
			(size 0.519938 1.4986)
			(layers "F.Cu" "F.Mask" "F.Paste")
			(net "M_H_CPU1_SB_DQS_DN<4>")
		)
		(pad "239" smd rect
			(at 2.050034 21.67509 90)
			(size 0.519938 1.4986)
			(layers "F.Cu" "F.Mask" "F.Paste")
			(net "M_H_CPU1_SB_DQS_DP<4>")
		)
		(pad "240" smd rect
			(at 2.050034 22.524974 90)
			(size 0.519938 1.4986)
			(layers "F.Cu" "F.Mask" "F.Paste")
			(net "GND")
		)
		(pad "241" smd rect
			(at 2.050034 23.375112 90)
			(size 0.519938 1.4986)
			(layers "F.Cu" "F.Mask" "F.Paste")
			(net "M_H_CPU1_SB_CB<2>")
		)
		(pad "242" smd rect
			(at 2.050034 24.224996 90)
			(size 0.519938 1.4986)
			(layers "F.Cu" "F.Mask" "F.Paste")
			(net "GND")
		)
		(pad "243" smd rect
			(at 2.050034 25.07488 90)
			(size 0.519938 1.4986)
			(layers "F.Cu" "F.Mask" "F.Paste")
			(net "M_H_CPU1_SB_CB<3>")
		)
		(pad "244" smd rect
			(at 2.050034 25.925018 90)
			(size 0.519938 1.4986)
			(layers "F.Cu" "F.Mask" "F.Paste")
			(net "GND")
		)
		(pad "245" smd rect
			(at 2.050034 26.774902 90)
			(size 0.519938 1.4986)
			(layers "F.Cu" "F.Mask" "F.Paste")
			(net "M_H_CPU1_SB_DQ<2>")
		)
		(pad "246" smd rect
			(at 2.050034 27.62504 90)
			(size 0.519938 1.4986)
			(layers "F.Cu" "F.Mask" "F.Paste")
			(net "GND")
		)
		(pad "247" smd rect
			(at 2.050034 28.474924 90)
			(size 0.519938 1.4986)
			(layers "F.Cu" "F.Mask" "F.Paste")
			(net "M_H_CPU1_SB_DQ<3>")
		)
		(pad "248" smd rect
			(at 2.050034 29.325062 90)
			(size 0.519938 1.4986)
			(layers "F.Cu" "F.Mask" "F.Paste")
			(net "GND")
		)
		(pad "249" smd rect
			(at 2.050034 30.174946 90)
			(size 0.519938 1.4986)
			(layers "F.Cu" "F.Mask" "F.Paste")
			(net "M_H_CPU1_SB_DQS_DN<5>")
		)
		(pad "250" smd rect
			(at 2.050034 31.025084 90)
			(size 0.519938 1.4986)
			(layers "F.Cu" "F.Mask" "F.Paste")
			(net "M_H_CPU1_SB_DQS_DP<5>")
		)
		(pad "251" smd rect
			(at 2.050034 31.874968 90)
			(size 0.519938 1.4986)
			(layers "F.Cu" "F.Mask" "F.Paste")
			(net "GND")
		)
		(pad "252" smd rect
			(at 2.050034 32.725106 90)
			(size 0.519938 1.4986)
			(layers "F.Cu" "F.Mask" "F.Paste")
			(net "M_H_CPU1_SB_DQ<6>")
		)
		(pad "253" smd rect
			(at 2.050034 33.57499 90)
			(size 0.519938 1.4986)
			(layers "F.Cu" "F.Mask" "F.Paste")
			(net "GND")
		)
		(pad "254" smd rect
			(at 2.050034 34.425128 90)
			(size 0.519938 1.4986)
			(layers "F.Cu" "F.Mask" "F.Paste")
			(net "M_H_CPU1_SB_DQ<7>")
		)
		(pad "255" smd rect
			(at 2.050034 35.275012 90)
			(size 0.519938 1.4986)
			(layers "F.Cu" "F.Mask" "F.Paste")
			(net "GND")
		)
		(pad "256" smd rect
			(at 2.050034 36.124896 90)
			(size 0.519938 1.4986)
			(layers "F.Cu" "F.Mask" "F.Paste")
			(net "M_H_CPU1_SB_DQ<10>")
		)
		(pad "257" smd rect
			(at 2.050034 36.975034 90)
			(size 0.519938 1.4986)
			(layers "F.Cu" "F.Mask" "F.Paste")
			(net "GND")
		)
		(pad "258" smd rect
			(at 2.050034 37.824918 90)
			(size 0.519938 1.4986)
			(layers "F.Cu" "F.Mask" "F.Paste")
			(net "M_H_CPU1_SB_DQ<11>")
		)
		(pad "259" smd rect
			(at 2.050034 38.675056 90)
			(size 0.519938 1.4986)
			(layers "F.Cu" "F.Mask" "F.Paste")
			(net "GND")
		)
		(pad "260" smd rect
			(at 2.050034 39.52494 90)
			(size 0.519938 1.4986)
			(layers "F.Cu" "F.Mask" "F.Paste")
			(net "M_H_CPU1_SB_DQS_DN<6>")
		)
		(pad "261" smd rect
			(at 2.050034 40.375078 90)
			(size 0.519938 1.4986)
			(layers "F.Cu" "F.Mask" "F.Paste")
			(net "M_H_CPU1_SB_DQS_DP<6>")
		)
		(pad "262" smd rect
			(at 2.050034 41.224962 90)
			(size 0.519938 1.4986)
			(layers "F.Cu" "F.Mask" "F.Paste")
			(net "GND")
		)
		(pad "263" smd rect
			(at 2.050034 42.0751 90)
			(size 0.519938 1.4986)
			(layers "F.Cu" "F.Mask" "F.Paste")
			(net "M_H_CPU1_SB_DQ<14>")
		)
		(pad "264" smd rect
			(at 2.050034 42.924984 90)
			(size 0.519938 1.4986)
			(layers "F.Cu" "F.Mask" "F.Paste")
			(net "GND")
		)
		(pad "265" smd rect
			(at 2.050034 43.775122 90)
			(size 0.519938 1.4986)
			(layers "F.Cu" "F.Mask" "F.Paste")
			(net "M_H_CPU1_SB_DQ<15>")
		)
		(pad "266" smd rect
			(at 2.050034 44.625006 90)
			(size 0.519938 1.4986)
			(layers "F.Cu" "F.Mask" "F.Paste")
			(net "GND")
		)
		(pad "267" smd rect
			(at 2.050034 45.47489 90)
			(size 0.519938 1.4986)
			(layers "F.Cu" "F.Mask" "F.Paste")
			(net "M_H_CPU1_SB_DQ<18>")
		)
		(pad "268" smd rect
			(at 2.050034 46.325028 90)
			(size 0.519938 1.4986)
			(layers "F.Cu" "F.Mask" "F.Paste")
			(net "GND")
		)
		(pad "269" smd rect
			(at 2.050034 47.174912 90)
			(size 0.519938 1.4986)
			(layers "F.Cu" "F.Mask" "F.Paste")
			(net "M_H_CPU1_SB_DQ<19>")
		)
		(pad "270" smd rect
			(at 2.050034 48.02505 90)
			(size 0.519938 1.4986)
			(layers "F.Cu" "F.Mask" "F.Paste")
			(net "GND")
		)
		(pad "271" smd rect
			(at 2.050034 48.874934 90)
			(size 0.519938 1.4986)
			(layers "F.Cu" "F.Mask" "F.Paste")
			(net "M_H_CPU1_SB_DQS_DN<7>")
		)
		(pad "272" smd rect
			(at 2.050034 49.725072 90)
			(size 0.519938 1.4986)
			(layers "F.Cu" "F.Mask" "F.Paste")
			(net "M_H_CPU1_SB_DQS_DP<7>")
		)
		(pad "273" smd rect
			(at 2.050034 50.574956 90)
			(size 0.519938 1.4986)
			(layers "F.Cu" "F.Mask" "F.Paste")
			(net "GND")
		)
		(pad "274" smd rect
			(at 2.050034 51.425094 90)
			(size 0.519938 1.4986)
			(layers "F.Cu" "F.Mask" "F.Paste")
			(net "M_H_CPU1_SB_DQ<22>")
		)
		(pad "275" smd rect
			(at 2.050034 52.274978 90)
			(size 0.519938 1.4986)
			(layers "F.Cu" "F.Mask" "F.Paste")
			(net "GND")
		)
		(pad "276" smd rect
			(at 2.050034 53.125116 90)
			(size 0.519938 1.4986)
			(layers "F.Cu" "F.Mask" "F.Paste")
			(net "M_H_CPU1_SB_DQ<23>")
		)
	)
)
